# S9S_MB_2U (Grand Teton) — schematic netlist excerpt (pin names and nets, part order shuffled) for the footprints in the layout excerpt that follows; sources: Cadence DE-HDL packaged netlist, KiCad conversion of 03242023_DA0F0TMBIJ0_F0T_Motherboard_J_brd_V01_OCP.brd

C1035  Q_CAP  22UF 4V 20% X6S  pkg C0402  page 74 : A = PVCCIN_CPU0 ; B = GND
PR1786  Q_RES  3.3 1% CHIP  pkg 0402LF  page 267 : A = SW_PVCCIN_CPU0_BOOT2 ; B = SW_PVCCIN_CPU0_BOOT2_R

(kicad_pcb
	(version 20260206)
	(generator "pcbnew")
	(generator_version "10.0")
	(general
		(thickness 1.6)
		(legacy_teardrops no)
	)
	(paper "A4")
	(title_block
		(title "03242023_DA0F0TMBIJ0_F0T_Motherboard_J_brd_V01_OCP.brd")
		(comment 1 "Grand Teton / footprints 2878-2879 of 6105")
	)
	(layers
		(0 "F.Cu" signal "TOP")
		(4 "In1.Cu" signal "GND")
		(6 "In2.Cu" signal "IN1")
		(8 "In3.Cu" signal "GND1")
		(10 "In4.Cu" signal "IN2")
		(12 "In5.Cu" signal "GND2")
		(14 "In6.Cu" signal "IN3")
		(16 "In7.Cu" signal "GND3")
		(18 "In8.Cu" signal "VCC")
		(20 "In9.Cu" signal "VCC1")
		(22 "In10.Cu" signal "GND4")
		(24 "In11.Cu" signal "IN4")
		(26 "In12.Cu" signal "GND5")
		(28 "In13.Cu" signal "IN5")
		(30 "In14.Cu" signal "GND6")
		(32 "In15.Cu" signal "IN6")
		(34 "In16.Cu" signal "GND7")
		(2 "B.Cu" signal "BOTTOM")
		(9 "F.Adhes" user "F.Adhesive")
		(11 "B.Adhes" user "B.Adhesive")
		(13 "F.Paste" user "Package Geometry/Pastemask Top")
		(15 "B.Paste" user "Package Geometry/Pastemask Bottom")
		(5 "F.SilkS" user "Ref Des/Silkscreen Top")
		(7 "B.SilkS" user "Ref Des/Silkscreen Bottom")
		(1 "F.Mask" user "Board Geometry/Soldermask Top")
		(3 "B.Mask" user "Board Geometry/Soldermask Bottom")
		(17 "Dwgs.User" user "User.Drawings")
		(19 "Cmts.User" user "User.Comments")
		(21 "Eco1.User" user "User.Eco1")
		(23 "Eco2.User" user "User.Eco2")
		(25 "Edge.Cuts" user "Board Geometry/Outline")
		(27 "Margin" user)
		(31 "F.CrtYd" user "Package Geometry/Place Bound Top")
		(29 "B.CrtYd" user "Package Geometry/Place Bound Bottom")
		(35 "F.Fab" user "Ref Des/Assembly Top")
		(33 "B.Fab" user "Ref Des/Assembly Bottom")
	)
	(footprint ""
		(layer "F.Cu")
		(at 355.228144 -240.276888 90)
		(property "Reference" "C1035"
			(at 0 0 90)
			(layer "F.SilkS")
			(hide yes)
			(effects
				(font
					(size 1.27 1.27)
				)
			)
		)
		(property "Value" ""
			(at 0 0 90)
			(layer "F.Fab")
			(effects
				(font
					(size 1.27 1.27)
				)
			)
		)
		(duplicate_pad_numbers_are_jumpers no)
		(fp_line
			(start 0.7874 -0.4064)
			(end 0.7874 0.4064)
			(stroke
				(width 0.1524)
				(type default)
			)
			(layer "F.SilkS")
		)
		(fp_line
			(start -0.7874 -0.4064)
			(end 0.7874 -0.4064)
			(stroke
				(width 0.1524)
				(type default)
			)
			(layer "F.SilkS")
		)
		(fp_line
			(start 0.7874 0.4064)
			(end -0.7874 0.4064)
			(stroke
				(width 0.1524)
				(type default)
			)
			(layer "F.SilkS")
		)
		(fp_line
			(start -0.7874 0.4064)
			(end -0.7874 -0.4064)
			(stroke
				(width 0.1524)
				(type default)
			)
			(layer "F.SilkS")
		)
		(fp_line
			(start -0.12065 -0.305054)
			(end -0.12065 -0.2794)
			(stroke
				(width 0.1)
				(type default)
			)
			(layer "F.Fab")
		)
		(fp_line
			(start -0.67945 -0.305054)
			(end -0.12065 -0.305054)
			(stroke
				(width 0.1)
				(type default)
			)
			(layer "F.Fab")
		)
		(fp_line
			(start 0.67945 -0.3048)
			(end 0.67945 0.3048)
			(stroke
				(width 0.1)
				(type default)
			)
			(layer "F.Fab")
		)
		(fp_line
			(start 0.12065 -0.3048)
			(end 0.67945 -0.3048)
			(stroke
				(width 0.1)
				(type default)
			)
			(layer "F.Fab")
		)
		(fp_line
			(start 0.12065 -0.2794)
			(end 0.12065 -0.3048)
			(stroke
				(width 0.1)
				(type default)
			)
			(layer "F.Fab")
		)
		(fp_line
			(start -0.12065 -0.2794)
			(end 0.12065 -0.2794)
			(stroke
				(width 0.1)
				(type default)
			)
			(layer "F.Fab")
		)
		(fp_line
			(start 0.120396 0.2794)
			(end -0.12065 0.2794)
			(stroke
				(width 0.1)
				(type default)
			)
			(layer "F.Fab")
		)
		(fp_line
			(start -0.12065 0.2794)
			(end -0.12065 0.3048)
			(stroke
				(width 0.1)
				(type default)
			)
			(layer "F.Fab")
		)
		(fp_line
			(start 0.67945 0.3048)
			(end 0.120396 0.3048)
			(stroke
				(width 0.1)
				(type default)
			)
			(layer "F.Fab")
		)
		(fp_line
			(start 0.120396 0.3048)
			(end 0.120396 0.2794)
			(stroke
				(width 0.1)
				(type default)
			)
			(layer "F.Fab")
		)
		(fp_line
			(start -0.12065 0.3048)
			(end -0.67945 0.3048)
			(stroke
				(width 0.1)
				(type default)
			)
			(layer "F.Fab")
		)
		(fp_line
			(start -0.67945 0.3048)
			(end -0.67945 -0.305054)
			(stroke
				(width 0.1)
				(type default)
			)
			(layer "F.Fab")
		)
		(pad "1" smd circle
			(at -0.40005 0 90)
			(size 0 0)
			(layers "F.Cu" "F.Mask" "F.Paste")
			(net "PVCCIN_CPU0")
		)
		(pad "2" smd circle
			(at 0.40005 0 90)
			(size 0 0)
			(layers "F.Cu" "F.Mask" "F.Paste")
			(net "GND")
		)
	)
	(footprint ""
		(layer "F.Cu")
		(at 353.88423 -338.180172 90)
		(property "Reference" "PR1786"
			(at 0 0 90)
			(layer "F.SilkS")
			(hide yes)
			(effects
				(font
					(size 1.27 1.27)
				)
			)
		)
		(property "Value" ""
			(at 0 0 90)
			(layer "F.Fab")
			(effects
				(font
					(size 1.27 1.27)
				)
			)
		)
		(duplicate_pad_numbers_are_jumpers no)
		(fp_line
			(start 0.7874 -0.4064)
			(end 0.7874 0.4064)
			(stroke
				(width 0.1524)
				(type default)
			)
			(layer "F.SilkS")
		)
		(fp_line
			(start -0.7874 -0.4064)
			(end 0.7874 -0.4064)
			(stroke
				(width 0.1524)
				(type default)
			)
			(layer "F.SilkS")
		)
		(fp_line
			(start 0.7874 0.4064)
			(end -0.7874 0.4064)
			(stroke
				(width 0.1524)
				(type default)
			)
			(layer "F.SilkS")
		)
		(fp_line
			(start -0.7874 0.4064)
			(end -0.7874 -0.4064)
			(stroke
				(width 0.1524)
				(type default)
			)
			(layer "F.SilkS")
		)
		(fp_line
			(start -0.12065 -0.305054)
			(end -0.12065 -0.2794)
			(stroke
				(width 0.1)
				(type default)
			)
			(layer "F.Fab")
		)
		(fp_line
			(start -0.67945 -0.305054)
			(end -0.12065 -0.305054)
			(stroke
				(width 0.1)
				(type default)
			)
			(layer "F.Fab")
		)
		(fp_line
			(start 0.67945 -0.3048)
			(end 0.67945 0.3048)
			(stroke
				(width 0.1)
				(type default)
			)
			(layer "F.Fab")
		)
		(fp_line
			(start 0.12065 -0.3048)
			(end 0.67945 -0.3048)
			(stroke
				(width 0.1)
				(type default)
			)
			(layer "F.Fab")
		)
		(fp_line
			(start 0.12065 -0.2794)
			(end 0.12065 -0.3048)
			(stroke
				(width 0.1)
				(type default)
			)
			(layer "F.Fab")
		)
		(fp_line
			(start -0.12065 -0.2794)
			(end 0.12065 -0.2794)
			(stroke
				(width 0.1)
				(type default)
			)
			(layer "F.Fab")
		)
		(fp_line
			(start 0.120396 0.2794)
			(end -0.12065 0.2794)
			(stroke
				(width 0.1)
				(type default)
			)
			(layer "F.Fab")
		)
		(fp_line
			(start -0.12065 0.2794)
			(end -0.12065 0.3048)
			(stroke
				(width 0.1)
				(type default)
			)
			(layer "F.Fab")
		)
		(fp_line
			(start 0.67945 0.3048)
			(end 0.120396 0.3048)
			(stroke
				(width 0.1)
				(type default)
			)
			(layer "F.Fab")
		)
		(fp_line
			(start 0.120396 0.3048)
			(end 0.120396 0.2794)
			(stroke
				(width 0.1)
				(type default)
			)
			(layer "F.Fab")
		)
		(fp_line
			(start -0.12065 0.3048)
			(end -0.67945 0.3048)
			(stroke
				(width 0.1)
				(type default)
			)
			(layer "F.Fab")
		)
		(fp_line
			(start -0.67945 0.3048)
			(end -0.67945 -0.305054)
			(stroke
				(width 0.1)
				(type default)
			)
			(layer "F.Fab")
		)
		(pad "1" smd circle
			(at -0.40005 0 90)
			(size 0 0)
			(layers "F.Cu" "F.Mask" "F.Paste")
			(net "SW_PVCCIN_CPU0_BOOT2")
		)
		(pad "2" smd circle
			(at 0.40005 0 90)
			(size 0 0)
			(layers "F.Cu" "F.Mask" "F.Paste")
			(net "SW_PVCCIN_CPU0_BOOT2_R")
		)
	)
)
